;LEADER: 12 
;HEADER: 
;CODE  : ASCII 
;FILE  : 9332_F0TG_MB_C_V02_0417_0820-bd-18-9.drl for backdrilling ... from layer BOTTOM to layer VCC
;DESIGN: 9332_F0TG_MB_C_V02_0417_0820.brd
;MUST-NOT-CUT-LAYER = GND3,  MAX_DRILL_DEPTH = 55.40 MILS,  MFG_STUB_LENGTH = 0.00 MILS
;   BackdrillSize 1. = 21.170000 Tolerance = +0.000000/-0.000000 NON_PLATED MILS Quantity = 150
%
G90
X0337205Y1686180
X0352953Y1686180
X0329331Y1682244
X0337205Y1681456
X0345079Y1682244
X0352953Y1681456
X0329331Y1677519
X0345079Y1677519
X0305709Y1686180
X0321457Y1686180
X0297835Y1682244
X0305709Y1681456
X0313583Y1682244
X0321457Y1681456
X0297835Y1677519
X0313583Y1677519
X0270275Y1686180
X0286023Y1686180
X0262401Y1682244
X0270275Y1681456
X0278149Y1682244
X0286023Y1681456
X0262401Y1677519
X0278149Y1677519
X0270275Y1672007
X0286023Y1672007
X0270275Y1667283
X0278149Y1668070
X0286023Y1667283
X0278149Y1663346
X0270275Y1657834
X0286023Y1657834
X0270275Y1653110
X0278149Y1653897
X0286023Y1653110
X0278149Y1649173
X0238779Y1686180
X0254527Y1686180
X0230905Y1682244
X0238779Y1681456
X0246653Y1682244
X0254527Y1681456
X0230905Y1677519
X0246653Y1677519
X0254527Y1672007
X0230905Y1668070
X0246653Y1668070
X0254527Y1667283
X0230905Y1663346
X0246653Y1663346
X0238779Y1657834
X0230905Y1653897
X0238779Y1653110
X0230905Y1649173
X0534448Y1686180
X0550196Y1686180
X0526574Y1682244
X0534448Y1681456
X0542322Y1682244
X0550196Y1681456
X0526574Y1677519
X0542322Y1677519
X0502952Y1686180
X0518700Y1686180
X0495078Y1682244
X0502952Y1681456
X0510826Y1682244
X0518700Y1681456
X0495078Y1677519
X0510826Y1677519
X0601378Y1686180
X0617126Y1686180
X0593504Y1682244
X0601378Y1681456
X0609252Y1682244
X0617126Y1681456
X0593504Y1677519
X0609252Y1677519
X0569882Y1686180
X0585630Y1686180
X0562008Y1682244
X0569882Y1681456
X0577756Y1682244
X0585630Y1681456
X0562008Y1677519
X0577756Y1677519
X1345078Y1686180
X1360826Y1686180
X1337204Y1682244
X1345078Y1681456
X1352952Y1682244
X1360826Y1681456
X1337204Y1677519
X1352952Y1677519
X1313582Y1686180
X1329330Y1686180
X1305708Y1682244
X1313582Y1681456
X1321456Y1682244
X1329330Y1681456
X1305708Y1677519
X1321456Y1677519
X1278148Y1686180
X1293896Y1686180
X1270274Y1682244
X1278148Y1681456
X1286022Y1682244
X1293896Y1681456
X1270274Y1677519
X1286022Y1677519
X1246652Y1686180
X1262400Y1686180
X1238778Y1682244
X1246652Y1681456
X1254526Y1682244
X1262400Y1681456
X1238778Y1677519
X1254526Y1677519
X1542322Y1686180
X1558070Y1686180
X1534448Y1682244
X1542322Y1681456
X1550196Y1682244
X1558070Y1681456
X1534448Y1677519
X1550196Y1677519
X1510826Y1686180
X1526574Y1686180
X1502952Y1682244
X1510826Y1681456
X1518700Y1682244
X1526574Y1681456
X1502952Y1677519
X1518700Y1677519
X1609252Y1686180
X1625000Y1686180
X1601378Y1682244
X1609252Y1681456
X1617126Y1682244
X1625000Y1681456
X1601378Y1677519
X1617126Y1677519
X1577756Y1686180
X1593504Y1686180
X1569882Y1682244
X1577756Y1681456
X1585630Y1682244
X1593504Y1681456
X1569882Y1677519
X1585630Y1677519
M30
